# SCM (Grand Teton) — schematic netlist excerpt (pin names and nets, part order shuffled) for the footprints in the layout excerpt that follows; sources: Cadence DE-HDL packaged netlist, KiCad conversion of 12092022_DA0F0TMDCD0_F0T_Management_Board_D_brd_V3_OCP.brd

R341  Q_RES  120 1% CHIP  pkg 0402LF  page 20 : A = GND ; B = M_BMC_DDR4_MCAS_N
R161  Q_RES  4.7K 1% CHIP  pkg 0402LF  page 11 : A = P3V3_AUX ; B = RMII_CSRDV

(kicad_pcb
	(version 20260206)
	(generator "pcbnew")
	(generator_version "10.0")
	(general
		(thickness 1.6)
		(legacy_teardrops no)
	)
	(paper "A4")
	(title_block
		(title "12092022_DA0F0TMDCD0_F0T_Management_Board_D_brd_V3_OCP.brd")
		(comment 1 "Grand Teton / footprints 87-88 of 1440")
	)
	(layers
		(0 "F.Cu" signal "TOP")
		(4 "In1.Cu" signal "GND")
		(6 "In2.Cu" signal "IN1")
		(8 "In3.Cu" signal "GND1")
		(10 "In4.Cu" signal "IN2")
		(12 "In5.Cu" signal "VCC")
		(14 "In6.Cu" signal "VCC1")
		(16 "In7.Cu" signal "IN3")
		(18 "In8.Cu" signal "GND2")
		(20 "In9.Cu" signal "IN4")
		(22 "In10.Cu" signal "GND3")
		(2 "B.Cu" signal "BOTTOM")
		(9 "F.Adhes" user "F.Adhesive")
		(11 "B.Adhes" user "B.Adhesive")
		(13 "F.Paste" user "Package Geometry/Pastemask Top")
		(15 "B.Paste" user "Package Geometry/Pastemask Bottom")
		(5 "F.SilkS" user "Ref Des/Silkscreen Top")
		(7 "B.SilkS" user "Ref Des/Silkscreen Bottom")
		(1 "F.Mask" user "Board Geometry/Soldermask Top")
		(3 "B.Mask" user "Board Geometry/Soldermask Bottom")
		(17 "Dwgs.User" user "User.Drawings")
		(19 "Cmts.User" user "User.Comments")
		(21 "Eco1.User" user "User.Eco1")
		(23 "Eco2.User" user "User.Eco2")
		(25 "Edge.Cuts" user "Board Geometry/Outline")
		(27 "Margin" user)
		(31 "F.CrtYd" user "Package Geometry/Place Bound Top")
		(29 "B.CrtYd" user "Package Geometry/Place Bound Bottom")
		(35 "F.Fab" user "Ref Des/Assembly Top")
		(33 "B.Fab" user "Ref Des/Assembly Bottom")
	)
	(footprint ""
		(layer "F.Cu")
		(at 51.6636 -109.3978 90)
		(property "Reference" "R161"
			(at 0 0 90)
			(layer "F.SilkS")
			(hide yes)
			(effects
				(font
					(size 1.27 1.27)
				)
			)
		)
		(property "Value" ""
			(at 0 0 90)
			(layer "F.Fab")
			(effects
				(font
					(size 1.27 1.27)
				)
			)
		)
		(duplicate_pad_numbers_are_jumpers no)
		(fp_line
			(start 0.7874 -0.4064)
			(end 0.7874 0.4064)
			(stroke
				(width 0.1524)
				(type default)
			)
			(layer "F.SilkS")
		)
		(fp_line
			(start -0.7874 -0.4064)
			(end 0.7874 -0.4064)
			(stroke
				(width 0.1524)
				(type default)
			)
			(layer "F.SilkS")
		)
		(fp_line
			(start 0.7874 0.4064)
			(end -0.7874 0.4064)
			(stroke
				(width 0.1524)
				(type default)
			)
			(layer "F.SilkS")
		)
		(fp_line
			(start -0.7874 0.4064)
			(end -0.7874 -0.4064)
			(stroke
				(width 0.1524)
				(type default)
			)
			(layer "F.SilkS")
		)
		(fp_line
			(start -0.12065 -0.305054)
			(end -0.12065 -0.2794)
			(stroke
				(width 0.1)
				(type default)
			)
			(layer "F.Fab")
		)
		(fp_line
			(start -0.67945 -0.305054)
			(end -0.12065 -0.305054)
			(stroke
				(width 0.1)
				(type default)
			)
			(layer "F.Fab")
		)
		(fp_line
			(start 0.67945 -0.3048)
			(end 0.67945 0.3048)
			(stroke
				(width 0.1)
				(type default)
			)
			(layer "F.Fab")
		)
		(fp_line
			(start 0.12065 -0.3048)
			(end 0.67945 -0.3048)
			(stroke
				(width 0.1)
				(type default)
			)
			(layer "F.Fab")
		)
		(fp_line
			(start 0.12065 -0.2794)
			(end 0.12065 -0.3048)
			(stroke
				(width 0.1)
				(type default)
			)
			(layer "F.Fab")
		)
		(fp_line
			(start -0.12065 -0.2794)
			(end 0.12065 -0.2794)
			(stroke
				(width 0.1)
				(type default)
			)
			(layer "F.Fab")
		)
		(fp_line
			(start 0.120396 0.2794)
			(end -0.12065 0.2794)
			(stroke
				(width 0.1)
				(type default)
			)
			(layer "F.Fab")
		)
		(fp_line
			(start -0.12065 0.2794)
			(end -0.12065 0.3048)
			(stroke
				(width 0.1)
				(type default)
			)
			(layer "F.Fab")
		)
		(fp_line
			(start 0.67945 0.3048)
			(end 0.120396 0.3048)
			(stroke
				(width 0.1)
				(type default)
			)
			(layer "F.Fab")
		)
		(fp_line
			(start 0.120396 0.3048)
			(end 0.120396 0.2794)
			(stroke
				(width 0.1)
				(type default)
			)
			(layer "F.Fab")
		)
		(fp_line
			(start -0.12065 0.3048)
			(end -0.67945 0.3048)
			(stroke
				(width 0.1)
				(type default)
			)
			(layer "F.Fab")
		)
		(fp_line
			(start -0.67945 0.3048)
			(end -0.67945 -0.305054)
			(stroke
				(width 0.1)
				(type default)
			)
			(layer "F.Fab")
		)
		(pad "1" smd circle
			(at -0.40005 0 90)
			(size 0 0)
			(layers "F.Cu" "F.Mask" "F.Paste")
			(net "P3V3_AUX")
		)
		(pad "2" smd circle
			(at 0.40005 0 90)
			(size 0 0)
			(layers "F.Cu" "F.Mask" "F.Paste")
			(net "RMII_CSRDV")
		)
	)
	(footprint ""
		(layer "F.Cu")
		(at 85.29955 -48.237394 180)
		(property "Reference" "R341"
			(at 0 0 180)
			(layer "F.SilkS")
			(hide yes)
			(effects
				(font
					(size 1.27 1.27)
				)
			)
		)
		(property "Value" ""
			(at 0 0 180)
			(layer "F.Fab")
			(effects
				(font
					(size 1.27 1.27)
				)
			)
		)
		(duplicate_pad_numbers_are_jumpers no)
		(fp_line
			(start 0.7874 0.4064)
			(end -0.7874 0.4064)
			(stroke
				(width 0.1524)
				(type default)
			)
			(layer "F.SilkS")
		)
		(fp_line
			(start 0.7874 -0.4064)
			(end 0.7874 0.4064)
			(stroke
				(width 0.1524)
				(type default)
			)
			(layer "F.SilkS")
		)
		(fp_line
			(start -0.7874 0.4064)
			(end -0.7874 -0.4064)
			(stroke
				(width 0.1524)
				(type default)
			)
			(layer "F.SilkS")
		)
		(fp_line
			(start -0.7874 -0.4064)
			(end 0.7874 -0.4064)
			(stroke
				(width 0.1524)
				(type default)
			)
			(layer "F.SilkS")
		)
		(fp_line
			(start 0.67945 0.3048)
			(end 0.120396 0.3048)
			(stroke
				(width 0.1)
				(type default)
			)
			(layer "F.Fab")
		)
		(fp_line
			(start 0.67945 -0.3048)
			(end 0.67945 0.3048)
			(stroke
				(width 0.1)
				(type default)
			)
			(layer "F.Fab")
		)
		(fp_line
			(start 0.12065 -0.2794)
			(end 0.12065 -0.3048)
			(stroke
				(width 0.1)
				(type default)
			)
			(layer "F.Fab")
		)
		(fp_line
			(start 0.12065 -0.3048)
			(end 0.67945 -0.3048)
			(stroke
				(width 0.1)
				(type default)
			)
			(layer "F.Fab")
		)
		(fp_line
			(start 0.120396 0.3048)
			(end 0.120396 0.2794)
			(stroke
				(width 0.1)
				(type default)
			)
			(layer "F.Fab")
		)
		(fp_line
			(start 0.120396 0.2794)
			(end -0.12065 0.2794)
			(stroke
				(width 0.1)
				(type default)
			)
			(layer "F.Fab")
		)
		(fp_line
			(start -0.12065 0.3048)
			(end -0.67945 0.3048)
			(stroke
				(width 0.1)
				(type default)
			)
			(layer "F.Fab")
		)
		(fp_line
			(start -0.12065 0.2794)
			(end -0.12065 0.3048)
			(stroke
				(width 0.1)
				(type default)
			)
			(layer "F.Fab")
		)
		(fp_line
			(start -0.12065 -0.2794)
			(end 0.12065 -0.2794)
			(stroke
				(width 0.1)
				(type default)
			)
			(layer "F.Fab")
		)
		(fp_line
			(start -0.12065 -0.305054)
			(end -0.12065 -0.2794)
			(stroke
				(width 0.1)
				(type default)
			)
			(layer "F.Fab")
		)
		(fp_line
			(start -0.67945 0.3048)
			(end -0.67945 -0.305054)
			(stroke
				(width 0.1)
				(type default)
			)
			(layer "F.Fab")
		)
		(fp_line
			(start -0.67945 -0.305054)
			(end -0.12065 -0.305054)
			(stroke
				(width 0.1)
				(type default)
			)
			(layer "F.Fab")
		)
		(pad "1" smd circle
			(at -0.40005 0 180)
			(size 0 0)
			(layers "F.Cu" "F.Mask" "F.Paste")
			(net "GND")
		)
		(pad "2" smd circle
			(at 0.40005 0 180)
			(size 0 0)
			(layers "F.Cu" "F.Mask" "F.Paste")
			(net "M_BMC_DDR4_MCAS_N")
		)
	)
)
